# SCM (Grand Teton) — schematic netlist excerpt (pin names and nets, part order shuffled) for the footprints in the layout excerpt that follows; sources: Cadence DE-HDL packaged netlist, KiCad conversion of 12092022_DA0F0TMDCD0_F0T_Management_Board_D_brd_V3_OCP.brd

C216  Q_CAP  1UF 25V 10% X6S  pkg C0402  page 41 : A = VCCIO3 ; B = GND
C104  Q_CAP  1UF 25V 10% X6S  pkg C0402  page 16 : A = P1V0_AUX ; B = GND
C15  Q_CAP  10UF 6.3V 20% X6S  pkg C0402  page 20 : A = P1V2_AUX ; B = GND

(kicad_pcb
	(version 20260206)
	(generator "pcbnew")
	(generator_version "10.0")
	(general
		(thickness 1.6)
		(legacy_teardrops no)
	)
	(paper "A4")
	(title_block
		(title "12092022_DA0F0TMDCD0_F0T_Management_Board_D_brd_V3_OCP.brd")
		(comment 1 "Grand Teton / footprints 1368-1370 of 1440")
	)
	(layers
		(0 "F.Cu" signal "TOP")
		(4 "In1.Cu" signal "GND")
		(6 "In2.Cu" signal "IN1")
		(8 "In3.Cu" signal "GND1")
		(10 "In4.Cu" signal "IN2")
		(12 "In5.Cu" signal "VCC")
		(14 "In6.Cu" signal "VCC1")
		(16 "In7.Cu" signal "IN3")
		(18 "In8.Cu" signal "GND2")
		(20 "In9.Cu" signal "IN4")
		(22 "In10.Cu" signal "GND3")
		(2 "B.Cu" signal "BOTTOM")
		(9 "F.Adhes" user "F.Adhesive")
		(11 "B.Adhes" user "B.Adhesive")
		(13 "F.Paste" user "Package Geometry/Pastemask Top")
		(15 "B.Paste" user "Package Geometry/Pastemask Bottom")
		(5 "F.SilkS" user "Ref Des/Silkscreen Top")
		(7 "B.SilkS" user "Ref Des/Silkscreen Bottom")
		(1 "F.Mask" user "Board Geometry/Soldermask Top")
		(3 "B.Mask" user "Board Geometry/Soldermask Bottom")
		(17 "Dwgs.User" user "User.Drawings")
		(19 "Cmts.User" user "User.Comments")
		(21 "Eco1.User" user "User.Eco1")
		(23 "Eco2.User" user "User.Eco2")
		(25 "Edge.Cuts" user "Board Geometry/Outline")
		(27 "Margin" user)
		(31 "F.CrtYd" user "Package Geometry/Place Bound Top")
		(29 "B.CrtYd" user "Package Geometry/Place Bound Bottom")
		(35 "F.Fab" user "Ref Des/Assembly Top")
		(33 "B.Fab" user "Ref Des/Assembly Bottom")
	)
	(footprint ""
		(layer "B.Cu")
		(at 25.136856 -96.0882)
		(property "Reference" "C216"
			(at 0 0 0)
			(layer "B.SilkS")
			(hide yes)
			(effects
				(font
					(size 1.27 1.27)
				)
				(justify mirror)
			)
		)
		(property "Value" ""
			(at 0 0 0)
			(layer "B.Fab")
			(effects
				(font
					(size 1.27 1.27)
				)
				(justify mirror)
			)
		)
		(duplicate_pad_numbers_are_jumpers no)
		(fp_line
			(start -0.69215 -0.2921)
			(end -0.69215 0.2921)
			(stroke
				(width 0.1524)
				(type default)
			)
			(layer "B.SilkS")
		)
		(fp_line
			(start -0.69215 0.2921)
			(end 0.69215 0.2921)
			(stroke
				(width 0.1524)
				(type default)
			)
			(layer "B.SilkS")
		)
		(fp_line
			(start 0.69215 -0.2921)
			(end -0.69215 -0.2921)
			(stroke
				(width 0.1524)
				(type default)
			)
			(layer "B.SilkS")
		)
		(fp_line
			(start 0.69215 0.2921)
			(end 0.69215 -0.2921)
			(stroke
				(width 0.1524)
				(type default)
			)
			(layer "B.SilkS")
		)
		(fp_line
			(start -0.51435 -0.2794)
			(end -0.51435 0.2794)
			(stroke
				(width 0.1)
				(type default)
			)
			(layer "B.Fab")
		)
		(fp_line
			(start -0.51435 0.2794)
			(end 0.51435 0.2794)
			(stroke
				(width 0.1)
				(type default)
			)
			(layer "B.Fab")
		)
		(fp_line
			(start 0.51435 -0.2794)
			(end -0.51435 -0.2794)
			(stroke
				(width 0.1)
				(type default)
			)
			(layer "B.Fab")
		)
		(fp_line
			(start 0.51435 0.2794)
			(end 0.51435 -0.2794)
			(stroke
				(width 0.1)
				(type default)
			)
			(layer "B.Fab")
		)
		(pad "1" smd circle
			(at 0.40005 0 180)
			(size 0 0)
			(layers "B.Cu" "B.Mask" "B.Paste")
			(net "VCCIO3")
		)
		(pad "2" smd circle
			(at -0.40005 0 180)
			(size 0 0)
			(layers "B.Cu" "B.Mask" "B.Paste")
			(net "GND")
		)
		(zone
			(layer "B.Cu")
			(hatch none 0.5)
			(connect_pads
				(clearance 0)
			)
			(min_thickness 0.25)
			(keepout
				(tracks not_allowed)
				(vias allowed)
				(pads allowed)
				(copperpour not_allowed)
				(footprints allowed)
			)
			(placement
				(enabled no)
				(sheetname "")
			)
			(fill
				(thermal_gap 0.5)
				(thermal_bridge_width 0.5)
				(island_removal_mode 0)
			)
			(polygon
				(pts
					(xy 25.327356 -96.00057) (xy 25.235916 -95.942404) (xy 25.036526 -95.942404) (xy 24.946356 -96.00057)
					(xy 24.946356 -96.17583) (xy 25.036526 -96.23425) (xy 25.235916 -96.23425) (xy 25.327356 -96.176084)
				)
			)
		)
	)
	(footprint ""
		(layer "B.Cu")
		(at 83.018884 -38.13556 180)
		(property "Reference" "C15"
			(at 0 0 0)
			(layer "B.SilkS")
			(hide yes)
			(effects
				(font
					(size 1.27 1.27)
				)
				(justify mirror)
			)
		)
		(property "Value" ""
			(at 0 0 0)
			(layer "B.Fab")
			(effects
				(font
					(size 1.27 1.27)
				)
				(justify mirror)
			)
		)
		(duplicate_pad_numbers_are_jumpers no)
		(fp_line
			(start 0.7874 0.4064)
			(end 0.7874 -0.4064)
			(stroke
				(width 0.1524)
				(type default)
			)
			(layer "B.SilkS")
		)
		(fp_line
			(start 0.7874 -0.4064)
			(end -0.7874 -0.4064)
			(stroke
				(width 0.1524)
				(type default)
			)
			(layer "B.SilkS")
		)
		(fp_line
			(start -0.7874 0.4064)
			(end 0.7874 0.4064)
			(stroke
				(width 0.1524)
				(type default)
			)
			(layer "B.SilkS")
		)
		(fp_line
			(start -0.7874 -0.4064)
			(end -0.7874 0.4064)
			(stroke
				(width 0.1524)
				(type default)
			)
			(layer "B.SilkS")
		)
		(fp_line
			(start 0.67945 0.3048)
			(end 0.67945 -0.305054)
			(stroke
				(width 0.1)
				(type default)
			)
			(layer "B.Fab")
		)
		(fp_line
			(start 0.67945 -0.305054)
			(end 0.12065 -0.305054)
			(stroke
				(width 0.1)
				(type default)
			)
			(layer "B.Fab")
		)
		(fp_line
			(start 0.12065 0.3048)
			(end 0.67945 0.3048)
			(stroke
				(width 0.1)
				(type default)
			)
			(layer "B.Fab")
		)
		(fp_line
			(start 0.12065 0.2794)
			(end 0.12065 0.3048)
			(stroke
				(width 0.1)
				(type default)
			)
			(layer "B.Fab")
		)
		(fp_line
			(start 0.12065 -0.2794)
			(end -0.12065 -0.2794)
			(stroke
				(width 0.1)
				(type default)
			)
			(layer "B.Fab")
		)
		(fp_line
			(start 0.12065 -0.305054)
			(end 0.12065 -0.2794)
			(stroke
				(width 0.1)
				(type default)
			)
			(layer "B.Fab")
		)
		(fp_line
			(start -0.120396 0.3048)
			(end -0.120396 0.2794)
			(stroke
				(width 0.1)
				(type default)
			)
			(layer "B.Fab")
		)
		(fp_line
			(start -0.120396 0.2794)
			(end 0.12065 0.2794)
			(stroke
				(width 0.1)
				(type default)
			)
			(layer "B.Fab")
		)
		(fp_line
			(start -0.12065 -0.2794)
			(end -0.12065 -0.3048)
			(stroke
				(width 0.1)
				(type default)
			)
			(layer "B.Fab")
		)
		(fp_line
			(start -0.12065 -0.3048)
			(end -0.67945 -0.3048)
			(stroke
				(width 0.1)
				(type default)
			)
			(layer "B.Fab")
		)
		(fp_line
			(start -0.67945 0.3048)
			(end -0.120396 0.3048)
			(stroke
				(width 0.1)
				(type default)
			)
			(layer "B.Fab")
		)
		(fp_line
			(start -0.67945 -0.3048)
			(end -0.67945 0.3048)
			(stroke
				(width 0.1)
				(type default)
			)
			(layer "B.Fab")
		)
		(pad "1" smd circle
			(at 0.40005 0)
			(size 0 0)
			(layers "B.Cu" "B.Mask" "B.Paste")
			(net "P1V2_AUX")
		)
		(pad "2" smd circle
			(at -0.40005 0)
			(size 0 0)
			(layers "B.Cu" "B.Mask" "B.Paste")
			(net "GND")
		)
	)
	(footprint ""
		(layer "B.Cu")
		(at 58.44413 -47.990252)
		(property "Reference" "C104"
			(at 0 0 0)
			(layer "B.SilkS")
			(hide yes)
			(effects
				(font
					(size 1.27 1.27)
				)
				(justify mirror)
			)
		)
		(property "Value" ""
			(at 0 0 0)
			(layer "B.Fab")
			(effects
				(font
					(size 1.27 1.27)
				)
				(justify mirror)
			)
		)
		(duplicate_pad_numbers_are_jumpers no)
		(fp_line
			(start -0.7874 -0.4064)
			(end -0.7874 0.4064)
			(stroke
				(width 0.1524)
				(type default)
			)
			(layer "B.SilkS")
		)
		(fp_line
			(start -0.7874 0.4064)
			(end 0.7874 0.4064)
			(stroke
				(width 0.1524)
				(type default)
			)
			(layer "B.SilkS")
		)
		(fp_line
			(start 0.7874 -0.4064)
			(end -0.7874 -0.4064)
			(stroke
				(width 0.1524)
				(type default)
			)
			(layer "B.SilkS")
		)
		(fp_line
			(start 0.7874 0.4064)
			(end 0.7874 -0.4064)
			(stroke
				(width 0.1524)
				(type default)
			)
			(layer "B.SilkS")
		)
		(fp_line
			(start -0.67945 -0.3048)
			(end -0.67945 0.3048)
			(stroke
				(width 0.1)
				(type default)
			)
			(layer "B.Fab")
		)
		(fp_line
			(start -0.67945 0.3048)
			(end -0.120396 0.3048)
			(stroke
				(width 0.1)
				(type default)
			)
			(layer "B.Fab")
		)
		(fp_line
			(start -0.12065 -0.3048)
			(end -0.67945 -0.3048)
			(stroke
				(width 0.1)
				(type default)
			)
			(layer "B.Fab")
		)
		(fp_line
			(start -0.12065 -0.2794)
			(end -0.12065 -0.3048)
			(stroke
				(width 0.1)
				(type default)
			)
			(layer "B.Fab")
		)
		(fp_line
			(start -0.120396 0.2794)
			(end 0.12065 0.2794)
			(stroke
				(width 0.1)
				(type default)
			)
			(layer "B.Fab")
		)
		(fp_line
			(start -0.120396 0.3048)
			(end -0.120396 0.2794)
			(stroke
				(width 0.1)
				(type default)
			)
			(layer "B.Fab")
		)
		(fp_line
			(start 0.12065 -0.305054)
			(end 0.12065 -0.2794)
			(stroke
				(width 0.1)
				(type default)
			)
			(layer "B.Fab")
		)
		(fp_line
			(start 0.12065 -0.2794)
			(end -0.12065 -0.2794)
			(stroke
				(width 0.1)
				(type default)
			)
			(layer "B.Fab")
		)
		(fp_line
			(start 0.12065 0.2794)
			(end 0.12065 0.3048)
			(stroke
				(width 0.1)
				(type default)
			)
			(layer "B.Fab")
		)
		(fp_line
			(start 0.12065 0.3048)
			(end 0.67945 0.3048)
			(stroke
				(width 0.1)
				(type default)
			)
			(layer "B.Fab")
		)
		(fp_line
			(start 0.67945 -0.305054)
			(end 0.12065 -0.305054)
			(stroke
				(width 0.1)
				(type default)
			)
			(layer "B.Fab")
		)
		(fp_line
			(start 0.67945 0.3048)
			(end 0.67945 -0.305054)
			(stroke
				(width 0.1)
				(type default)
			)
			(layer "B.Fab")
		)
		(pad "1" smd circle
			(at 0.40005 0 180)
			(size 0 0)
			(layers "B.Cu" "B.Mask" "B.Paste")
			(net "P1V0_AUX")
		)
		(pad "2" smd circle
			(at -0.40005 0 180)
			(size 0 0)
			(layers "B.Cu" "B.Mask" "B.Paste")
			(net "GND")
		)
	)
)
